FILE_TYPE = MACRO_DRAWING;
SET COLOR_WIRE YELLOW;
SET COLOR_PROP MONO;
SET COLOR_DOT WHITE;
SET COLOR_ARC YELLOW;
SET COLOR_BODY GREEN;
SET COLOR_NOTE MONO;
SET PROP_DISPLAY VALUE;
SET PAGE_NUMBER P6;
FORCEADD INTEL_CORP_BPAGE..1
(250 -50);
FORCEPROP 1 LAST CUSTOM_TXT_CDS <CURRENT_DESIGN_SHEET> OF <TOTAL_DESIGN_SHEETS>
J 0
(-250 -25);
PAINT GREEN (-250 -25);
FORCEPROP 1 LAST CUSTOM_TXT_CDS <CON_LAST_MODIFIED>
J 0
(-1675 300);
PAINT GREEN (-1675 300);
FORCEPROP 2 LAST CUSTOM_TXT_CDS <XR_PAGE_TITLE>
J 0
(-7640 5200);
DISPLAY 0.638298 (-7640 5200);
PAINT PINK (-7640 5200);
DISPLAY INVISIBLE (-7640 5200);
FORCEPROP 1 LAST SCH_NUMBER H4694802
J 0
(-1050 100);
DISPLAY 1.212766 (-1050 100);
PAINT YELLOW (-1050 100);
FORCEPROP 1 LAST SCH_DEPT BESD
J 1
(-4200 50);
DISPLAY 1.212766 (-4200 50);
PAINT YELLOW (-4200 50);
FORCEPROP 1 LAST SCH_REV 2.420
J 0
(0 100);
DISPLAY 0.978723 (0 100);
PAINT YELLOW (0 100);
FORCEPROP 1 LAST SCH_ADDRESS3 Santa Clara, CA 95052-8119
J 0
(-3725 -25);
DISPLAY 0.617021 (-3725 -25);
PAINT GREEN (-3725 -25);
FORCEPROP 1 LAST SCH_ADDRESS2 P.O. BOX 58119
J 0
(-3725 25);
DISPLAY 0.617021 (-3725 25);
PAINT GREEN (-3725 25);
FORCEPROP 1 LAST SCH_ADDRESS1 2200 Mission College Blvd.
J 0
(-3725 75);
DISPLAY 0.617021 (-3725 75);
PAINT GREEN (-3725 75);
FORCEPROP 1 LAST SCH_TITLE CLOCK BLOCK DIAGRAM
J 0
(-7700 0);
DISPLAY 1.212766 (-7700 0);
PAINT ORANGE (-7700 0);
FORCEPROP 2 LAST PAGE_BORDER TRUE
J 0
(-7640 5200);
PAINT PINK (-7640 5200);
DISPLAY INVISIBLE (-7640 5200);
FORCEPROP 2 LAST CDS_LIB mstr_symbols
J 0
(250 -50);
DISPLAY 1.595745 (250 -50);
PAINT ORANGE (250 -50);
DISPLAY INVISIBLE (250 -50);
FORCEPROP 1 LAST COMMENT_BODY TRUE
J 0
(262 -38);
DISPLAY 0.744681 (262 -38);
PAINT GREEN (262 -38);
DISPLAY INVISIBLE (262 -38);
FORCEPROP 1 LAST CDS_CON_LAST_MODIFIED Tue Dec 01 11:47:56 2015
J 0
(-1175 275);
DISPLAY 1.595745 (-1175 275);
PAINT GREEN (-1175 275);
DISPLAY INVISIBLE (-1175 275);
FORCEPROP 2 LAST CDS_XR_PAGE_TITLE CR-6 : @BASEBOARD_FAB2_LIB.BASEBOARD_FAB2(SCH_1):PAGE6
J 0
(-7640 5200);
DISPLAY 0.638298 (-7640 5200);
PAINT PINK (-7640 5200);
DISPLAY INVISIBLE (-7640 5200);
FORCENOTE
$CDS_IMAGE|06_CLOCK TOPOLOGY_0.jpg|6250|4250
(-4200 2600) 0;
DISPLAY CENTER (-4200 2600);
PAINT MONO (-4200 2600);
QUIT
